# S9S_MB_2U (Grand Teton) — schematic netlist excerpt (pin names and nets, part order shuffled) for the footprints in the layout excerpt that follows; sources: Cadence DE-HDL packaged netlist, KiCad conversion of 03242023_DA0F0TMBIJ0_F0T_Motherboard_J_brd_V01_OCP.brd

C835  Q_CAP_DIFFBUS  DIFF BUS_0.22UF 6.3V 20% X6S  pkg C0201  page 175 : \1\ = P5E_CPU1_PE1_TX_C_DP<1> ; \2\ = P5E_CPU1_PE1_TX_DP<1>

(kicad_pcb
	(version 20260206)
	(generator "pcbnew")
	(generator_version "10.0")
	(general
		(thickness 1.6)
		(legacy_teardrops no)
	)
	(paper "A4")
	(title_block
		(title "03242023_DA0F0TMBIJ0_F0T_Motherboard_J_brd_V01_OCP.brd")
		(comment 1 "Grand Teton / footprints 1507-1507 of 6105")
	)
	(layers
		(0 "F.Cu" signal "TOP")
		(4 "In1.Cu" signal "GND")
		(6 "In2.Cu" signal "IN1")
		(8 "In3.Cu" signal "GND1")
		(10 "In4.Cu" signal "IN2")
		(12 "In5.Cu" signal "GND2")
		(14 "In6.Cu" signal "IN3")
		(16 "In7.Cu" signal "GND3")
		(18 "In8.Cu" signal "VCC")
		(20 "In9.Cu" signal "VCC1")
		(22 "In10.Cu" signal "GND4")
		(24 "In11.Cu" signal "IN4")
		(26 "In12.Cu" signal "GND5")
		(28 "In13.Cu" signal "IN5")
		(30 "In14.Cu" signal "GND6")
		(32 "In15.Cu" signal "IN6")
		(34 "In16.Cu" signal "GND7")
		(2 "B.Cu" signal "BOTTOM")
		(9 "F.Adhes" user "F.Adhesive")
		(11 "B.Adhes" user "B.Adhesive")
		(13 "F.Paste" user "Package Geometry/Pastemask Top")
		(15 "B.Paste" user "Package Geometry/Pastemask Bottom")
		(5 "F.SilkS" user "Ref Des/Silkscreen Top")
		(7 "B.SilkS" user "Ref Des/Silkscreen Bottom")
		(1 "F.Mask" user "Board Geometry/Soldermask Top")
		(3 "B.Mask" user "Board Geometry/Soldermask Bottom")
		(17 "Dwgs.User" user "User.Drawings")
		(19 "Cmts.User" user "User.Comments")
		(21 "Eco1.User" user "User.Eco1")
		(23 "Eco2.User" user "User.Eco2")
		(25 "Edge.Cuts" user "Board Geometry/Outline")
		(27 "Margin" user)
		(31 "F.CrtYd" user "Package Geometry/Place Bound Top")
		(29 "B.CrtYd" user "Package Geometry/Place Bound Bottom")
		(35 "F.Fab" user "Ref Des/Assembly Top")
		(33 "B.Fab" user "Ref Des/Assembly Bottom")
	)
	(footprint ""
		(layer "F.Cu")
		(at 54.96433 -16.099536 90)
		(property "Reference" "C835"
			(at 0 0 90)
			(layer "F.SilkS")
			(hide yes)
			(effects
				(font
					(size 1.27 1.27)
				)
			)
		)
		(property "Value" ""
			(at 0 0 90)
			(layer "F.Fab")
			(effects
				(font
					(size 1.27 1.27)
				)
			)
		)
		(duplicate_pad_numbers_are_jumpers no)
		(fp_line
			(start 0.299974 -0.150114)
			(end 0.299974 0.150114)
			(stroke
				(width 0.1)
				(type default)
			)
			(layer "F.Fab")
		)
		(fp_line
			(start -0.299974 -0.150114)
			(end 0.299974 -0.150114)
			(stroke
				(width 0.1)
				(type default)
			)
			(layer "F.Fab")
		)
		(fp_line
			(start 0.299974 0.150114)
			(end -0.299974 0.150114)
			(stroke
				(width 0.1)
				(type default)
			)
			(layer "F.Fab")
		)
		(fp_line
			(start -0.299974 0.150114)
			(end -0.299974 -0.150114)
			(stroke
				(width 0.1)
				(type default)
			)
			(layer "F.Fab")
		)
		(pad "1" smd rect
			(at -0.2667 0 90)
			(size 0.3048 0.381)
			(layers "F.Cu" "F.Mask" "F.Paste")
			(net "P5E_CPU1_PE1_TX_C_DP<1>")
		)
		(pad "2" smd rect
			(at 0.2667 0 90)
			(size 0.3048 0.381)
			(layers "F.Cu" "F.Mask" "F.Paste")
			(net "P5E_CPU1_PE1_TX_DP<1>")
		)
	)
)
